# T6G (Grand Teton) — schematic netlist excerpt (pin names and nets, part order shuffled) for the footprints in the layout excerpt that follows; sources: Cadence DE-HDL packaged netlist, KiCad conversion of 04192023_DAF0TMB3IC0_F0TG_MB_C_brd_V02_OCP.brd

R3479  Q_RES  33.2 1% CHIP  pkg 0402LF  page 81 : A = GPU_BASE_STBY_EN_R ; B = GPU_BASE_STBY_EN
R4207  Q_RES  1K 1% CHIP  pkg 0402LF  page 235 : A = U270_0_ADD0 ; B = GND
C6713  Q_CAP_DIFFBUS  DIFF BUS_0.22UF 6.3V 20% X6S  pkg C0201  page 341 : \1\ = P5E_CPU1_P2_TX_BUF_C_DP<10> ; \2\ = P5E_CPU1_P2_TX_BUF_DP<10>

(kicad_pcb
	(version 20260206)
	(generator "pcbnew")
	(generator_version "10.0")
	(general
		(thickness 1.6)
		(legacy_teardrops no)
	)
	(paper "A4")
	(title_block
		(title "04192023_DAF0TMB3IC0_F0TG_MB_C_brd_V02_OCP.brd")
		(comment 1 "Grand Teton / footprints 563-565 of 8354")
	)
	(layers
		(0 "F.Cu" signal "TOP")
		(4 "In1.Cu" signal "GND")
		(6 "In2.Cu" signal "IN1")
		(8 "In3.Cu" signal "GND1")
		(10 "In4.Cu" signal "IN2")
		(12 "In5.Cu" signal "GND2")
		(14 "In6.Cu" signal "IN3")
		(16 "In7.Cu" signal "GND3")
		(18 "In8.Cu" signal "VCC")
		(20 "In9.Cu" signal "VCC1")
		(22 "In10.Cu" signal "GND4")
		(24 "In11.Cu" signal "IN4")
		(26 "In12.Cu" signal "GND5")
		(28 "In13.Cu" signal "IN5")
		(30 "In14.Cu" signal "GND6")
		(32 "In15.Cu" signal "IN6")
		(34 "In16.Cu" signal "GND7")
		(2 "B.Cu" signal "BOTTOM")
		(9 "F.Adhes" user "F.Adhesive")
		(11 "B.Adhes" user "B.Adhesive")
		(13 "F.Paste" user "Package Geometry/Pastemask Top")
		(15 "B.Paste" user "Package Geometry/Pastemask Bottom")
		(5 "F.SilkS" user "Ref Des/Silkscreen Top")
		(7 "B.SilkS" user "Ref Des/Silkscreen Bottom")
		(1 "F.Mask" user "Board Geometry/Soldermask Top")
		(3 "B.Mask" user "Board Geometry/Soldermask Bottom")
		(17 "Dwgs.User" user "User.Drawings")
		(19 "Cmts.User" user "User.Comments")
		(21 "Eco1.User" user "User.Eco1")
		(23 "Eco2.User" user "User.Eco2")
		(25 "Edge.Cuts" user "Board Geometry/Outline")
		(27 "Margin" user)
		(31 "F.CrtYd" user "Package Geometry/Place Bound Top")
		(29 "B.CrtYd" user "Package Geometry/Place Bound Bottom")
		(35 "F.Fab" user "Ref Des/Assembly Top")
		(33 "B.Fab" user "Ref Des/Assembly Bottom")
	)
	(footprint ""
		(layer "F.Cu")
		(at 367.685066 -424.002962 90)
		(property "Reference" "R4207"
			(at 0 0 90)
			(layer "F.SilkS")
			(hide yes)
			(effects
				(font
					(size 1.27 1.27)
				)
			)
		)
		(property "Value" ""
			(at 0 0 90)
			(layer "F.Fab")
			(effects
				(font
					(size 1.27 1.27)
				)
			)
		)
		(duplicate_pad_numbers_are_jumpers no)
		(fp_line
			(start 0.7874 -0.4064)
			(end 0.7874 0.4064)
			(stroke
				(width 0.1524)
				(type default)
			)
			(layer "F.SilkS")
		)
		(fp_line
			(start -0.7874 -0.4064)
			(end 0.7874 -0.4064)
			(stroke
				(width 0.1524)
				(type default)
			)
			(layer "F.SilkS")
		)
		(fp_line
			(start 0.7874 0.4064)
			(end -0.7874 0.4064)
			(stroke
				(width 0.1524)
				(type default)
			)
			(layer "F.SilkS")
		)
		(fp_line
			(start -0.7874 0.4064)
			(end -0.7874 -0.4064)
			(stroke
				(width 0.1524)
				(type default)
			)
			(layer "F.SilkS")
		)
		(fp_line
			(start -0.12065 -0.305054)
			(end -0.12065 -0.2794)
			(stroke
				(width 0.1)
				(type default)
			)
			(layer "F.Fab")
		)
		(fp_line
			(start -0.67945 -0.305054)
			(end -0.12065 -0.305054)
			(stroke
				(width 0.1)
				(type default)
			)
			(layer "F.Fab")
		)
		(fp_line
			(start 0.67945 -0.3048)
			(end 0.67945 0.3048)
			(stroke
				(width 0.1)
				(type default)
			)
			(layer "F.Fab")
		)
		(fp_line
			(start 0.12065 -0.3048)
			(end 0.67945 -0.3048)
			(stroke
				(width 0.1)
				(type default)
			)
			(layer "F.Fab")
		)
		(fp_line
			(start 0.12065 -0.2794)
			(end 0.12065 -0.3048)
			(stroke
				(width 0.1)
				(type default)
			)
			(layer "F.Fab")
		)
		(fp_line
			(start -0.12065 -0.2794)
			(end 0.12065 -0.2794)
			(stroke
				(width 0.1)
				(type default)
			)
			(layer "F.Fab")
		)
		(fp_line
			(start 0.120396 0.2794)
			(end -0.12065 0.2794)
			(stroke
				(width 0.1)
				(type default)
			)
			(layer "F.Fab")
		)
		(fp_line
			(start -0.12065 0.2794)
			(end -0.12065 0.3048)
			(stroke
				(width 0.1)
				(type default)
			)
			(layer "F.Fab")
		)
		(fp_line
			(start 0.67945 0.3048)
			(end 0.120396 0.3048)
			(stroke
				(width 0.1)
				(type default)
			)
			(layer "F.Fab")
		)
		(fp_line
			(start 0.120396 0.3048)
			(end 0.120396 0.2794)
			(stroke
				(width 0.1)
				(type default)
			)
			(layer "F.Fab")
		)
		(fp_line
			(start -0.12065 0.3048)
			(end -0.67945 0.3048)
			(stroke
				(width 0.1)
				(type default)
			)
			(layer "F.Fab")
		)
		(fp_line
			(start -0.67945 0.3048)
			(end -0.67945 -0.305054)
			(stroke
				(width 0.1)
				(type default)
			)
			(layer "F.Fab")
		)
		(pad "1" smd circle
			(at -0.40005 0 90)
			(size 0 0)
			(layers "F.Cu" "F.Mask" "F.Paste")
			(net "U270_0_ADD0")
		)
		(pad "2" smd circle
			(at 0.40005 0 90)
			(size 0 0)
			(layers "F.Cu" "F.Mask" "F.Paste")
			(net "GND")
		)
	)
	(footprint ""
		(layer "F.Cu")
		(at 197.269608 -125.817376)
		(property "Reference" "R3479"
			(at 0 0 0)
			(layer "F.SilkS")
			(hide yes)
			(effects
				(font
					(size 1.27 1.27)
				)
			)
		)
		(property "Value" ""
			(at 0 0 0)
			(layer "F.Fab")
			(effects
				(font
					(size 1.27 1.27)
				)
			)
		)
		(duplicate_pad_numbers_are_jumpers no)
		(fp_line
			(start -0.7874 -0.4064)
			(end 0.7874 -0.4064)
			(stroke
				(width 0.1524)
				(type default)
			)
			(layer "F.SilkS")
		)
		(fp_line
			(start -0.7874 0.4064)
			(end -0.7874 -0.4064)
			(stroke
				(width 0.1524)
				(type default)
			)
			(layer "F.SilkS")
		)
		(fp_line
			(start 0.7874 -0.4064)
			(end 0.7874 0.4064)
			(stroke
				(width 0.1524)
				(type default)
			)
			(layer "F.SilkS")
		)
		(fp_line
			(start 0.7874 0.4064)
			(end -0.7874 0.4064)
			(stroke
				(width 0.1524)
				(type default)
			)
			(layer "F.SilkS")
		)
		(fp_line
			(start -0.67945 -0.305054)
			(end -0.12065 -0.305054)
			(stroke
				(width 0.1)
				(type default)
			)
			(layer "F.Fab")
		)
		(fp_line
			(start -0.67945 0.3048)
			(end -0.67945 -0.305054)
			(stroke
				(width 0.1)
				(type default)
			)
			(layer "F.Fab")
		)
		(fp_line
			(start -0.12065 -0.305054)
			(end -0.12065 -0.2794)
			(stroke
				(width 0.1)
				(type default)
			)
			(layer "F.Fab")
		)
		(fp_line
			(start -0.12065 -0.2794)
			(end 0.12065 -0.2794)
			(stroke
				(width 0.1)
				(type default)
			)
			(layer "F.Fab")
		)
		(fp_line
			(start -0.12065 0.2794)
			(end -0.12065 0.3048)
			(stroke
				(width 0.1)
				(type default)
			)
			(layer "F.Fab")
		)
		(fp_line
			(start -0.12065 0.3048)
			(end -0.67945 0.3048)
			(stroke
				(width 0.1)
				(type default)
			)
			(layer "F.Fab")
		)
		(fp_line
			(start 0.120396 0.2794)
			(end -0.12065 0.2794)
			(stroke
				(width 0.1)
				(type default)
			)
			(layer "F.Fab")
		)
		(fp_line
			(start 0.120396 0.3048)
			(end 0.120396 0.2794)
			(stroke
				(width 0.1)
				(type default)
			)
			(layer "F.Fab")
		)
		(fp_line
			(start 0.12065 -0.3048)
			(end 0.67945 -0.3048)
			(stroke
				(width 0.1)
				(type default)
			)
			(layer "F.Fab")
		)
		(fp_line
			(start 0.12065 -0.2794)
			(end 0.12065 -0.3048)
			(stroke
				(width 0.1)
				(type default)
			)
			(layer "F.Fab")
		)
		(fp_line
			(start 0.67945 -0.3048)
			(end 0.67945 0.3048)
			(stroke
				(width 0.1)
				(type default)
			)
			(layer "F.Fab")
		)
		(fp_line
			(start 0.67945 0.3048)
			(end 0.120396 0.3048)
			(stroke
				(width 0.1)
				(type default)
			)
			(layer "F.Fab")
		)
		(pad "1" smd circle
			(at -0.40005 0)
			(size 0 0)
			(layers "F.Cu" "F.Mask" "F.Paste")
			(net "GPU_BASE_STBY_EN_R")
		)
		(pad "2" smd circle
			(at 0.40005 0)
			(size 0 0)
			(layers "F.Cu" "F.Mask" "F.Paste")
			(net "GPU_BASE_STBY_EN")
		)
	)
	(footprint ""
		(layer "F.Cu")
		(at 146.415506 -408.517344 -90)
		(property "Reference" "C6713"
			(at 0 0 270)
			(layer "F.SilkS")
			(hide yes)
			(effects
				(font
					(size 1.27 1.27)
				)
			)
		)
		(property "Value" ""
			(at 0 0 270)
			(layer "F.Fab")
			(effects
				(font
					(size 1.27 1.27)
				)
			)
		)
		(duplicate_pad_numbers_are_jumpers no)
		(fp_line
			(start -0.299974 0.150114)
			(end -0.299974 -0.150114)
			(stroke
				(width 0.1)
				(type default)
			)
			(layer "F.Fab")
		)
		(fp_line
			(start 0.299974 0.150114)
			(end -0.299974 0.150114)
			(stroke
				(width 0.1)
				(type default)
			)
			(layer "F.Fab")
		)
		(fp_line
			(start -0.299974 -0.150114)
			(end 0.299974 -0.150114)
			(stroke
				(width 0.1)
				(type default)
			)
			(layer "F.Fab")
		)
		(fp_line
			(start 0.299974 -0.150114)
			(end 0.299974 0.150114)
			(stroke
				(width 0.1)
				(type default)
			)
			(layer "F.Fab")
		)
		(pad "1" smd rect
			(at -0.2667 0 270)
			(size 0.3048 0.381)
			(layers "F.Cu" "F.Mask" "F.Paste")
			(net "P5E_CPU1_P2_TX_BUF_C_DP<10>")
		)
		(pad "2" smd rect
			(at 0.2667 0 270)
			(size 0.3048 0.381)
			(layers "F.Cu" "F.Mask" "F.Paste")
			(net "P5E_CPU1_P2_TX_BUF_DP<10>")
		)
	)
)
